FILE_TYPE = CONNECTIVITY;
{Allegro Design Entry HDL 17.4-2019 S026 (4007227) 1/17/2022}
"PAGE_NUMBER" = 3;
0"NC";
END.
